# S9S_MB_2U (Grand Teton) — schematic netlist excerpt (pin names and nets, part order shuffled) for the footprints in the layout excerpt that follows; sources: Cadence DE-HDL packaged netlist, KiCad conversion of 03242023_DA0F0TMBIJ0_F0T_Motherboard_J_brd_V01_OCP.brd

R2668  Q_RES  4.7K 5% EMPTY  pkg 0402LF  page 234 : A = P3V3_AUX ; B = I3C_BMC_SWB_BUF_R_SDA
R4165  Q_RES  4.7K 5% CHIP  pkg 0402LF  page 145 : A = P3V3_AUX ; B = GPU_3V3IO_RSVD4_N

(kicad_pcb
	(version 20260206)
	(generator "pcbnew")
	(generator_version "10.0")
	(general
		(thickness 1.6)
		(legacy_teardrops no)
	)
	(paper "A4")
	(title_block
		(title "03242023_DA0F0TMBIJ0_F0T_Motherboard_J_brd_V01_OCP.brd")
		(comment 1 "Grand Teton / footprints 331-332 of 6105")
	)
	(layers
		(0 "F.Cu" signal "TOP")
		(4 "In1.Cu" signal "GND")
		(6 "In2.Cu" signal "IN1")
		(8 "In3.Cu" signal "GND1")
		(10 "In4.Cu" signal "IN2")
		(12 "In5.Cu" signal "GND2")
		(14 "In6.Cu" signal "IN3")
		(16 "In7.Cu" signal "GND3")
		(18 "In8.Cu" signal "VCC")
		(20 "In9.Cu" signal "VCC1")
		(22 "In10.Cu" signal "GND4")
		(24 "In11.Cu" signal "IN4")
		(26 "In12.Cu" signal "GND5")
		(28 "In13.Cu" signal "IN5")
		(30 "In14.Cu" signal "GND6")
		(32 "In15.Cu" signal "IN6")
		(34 "In16.Cu" signal "GND7")
		(2 "B.Cu" signal "BOTTOM")
		(9 "F.Adhes" user "F.Adhesive")
		(11 "B.Adhes" user "B.Adhesive")
		(13 "F.Paste" user "Package Geometry/Pastemask Top")
		(15 "B.Paste" user "Package Geometry/Pastemask Bottom")
		(5 "F.SilkS" user "Ref Des/Silkscreen Top")
		(7 "B.SilkS" user "Ref Des/Silkscreen Bottom")
		(1 "F.Mask" user "Board Geometry/Soldermask Top")
		(3 "B.Mask" user "Board Geometry/Soldermask Bottom")
		(17 "Dwgs.User" user "User.Drawings")
		(19 "Cmts.User" user "User.Comments")
		(21 "Eco1.User" user "User.Eco1")
		(23 "Eco2.User" user "User.Eco2")
		(25 "Edge.Cuts" user "Board Geometry/Outline")
		(27 "Margin" user)
		(31 "F.CrtYd" user "Package Geometry/Place Bound Top")
		(29 "B.CrtYd" user "Package Geometry/Place Bound Bottom")
		(35 "F.Fab" user "Ref Des/Assembly Top")
		(33 "B.Fab" user "Ref Des/Assembly Bottom")
	)
	(footprint ""
		(layer "F.Cu")
		(at 357.735632 -397.519398)
		(property "Reference" "R2668"
			(at 0 0 0)
			(layer "F.SilkS")
			(hide yes)
			(effects
				(font
					(size 1.27 1.27)
				)
			)
		)
		(property "Value" ""
			(at 0 0 0)
			(layer "F.Fab")
			(effects
				(font
					(size 1.27 1.27)
				)
			)
		)
		(duplicate_pad_numbers_are_jumpers no)
		(fp_line
			(start -0.7874 -0.4064)
			(end 0.7874 -0.4064)
			(stroke
				(width 0.1524)
				(type default)
			)
			(layer "F.SilkS")
		)
		(fp_line
			(start -0.7874 0.4064)
			(end -0.7874 -0.4064)
			(stroke
				(width 0.1524)
				(type default)
			)
			(layer "F.SilkS")
		)
		(fp_line
			(start 0.7874 -0.4064)
			(end 0.7874 0.4064)
			(stroke
				(width 0.1524)
				(type default)
			)
			(layer "F.SilkS")
		)
		(fp_line
			(start 0.7874 0.4064)
			(end -0.7874 0.4064)
			(stroke
				(width 0.1524)
				(type default)
			)
			(layer "F.SilkS")
		)
		(fp_line
			(start -0.67945 -0.305054)
			(end -0.12065 -0.305054)
			(stroke
				(width 0.1)
				(type default)
			)
			(layer "F.Fab")
		)
		(fp_line
			(start -0.67945 0.3048)
			(end -0.67945 -0.305054)
			(stroke
				(width 0.1)
				(type default)
			)
			(layer "F.Fab")
		)
		(fp_line
			(start -0.12065 -0.305054)
			(end -0.12065 -0.2794)
			(stroke
				(width 0.1)
				(type default)
			)
			(layer "F.Fab")
		)
		(fp_line
			(start -0.12065 -0.2794)
			(end 0.12065 -0.2794)
			(stroke
				(width 0.1)
				(type default)
			)
			(layer "F.Fab")
		)
		(fp_line
			(start -0.12065 0.2794)
			(end -0.12065 0.3048)
			(stroke
				(width 0.1)
				(type default)
			)
			(layer "F.Fab")
		)
		(fp_line
			(start -0.12065 0.3048)
			(end -0.67945 0.3048)
			(stroke
				(width 0.1)
				(type default)
			)
			(layer "F.Fab")
		)
		(fp_line
			(start 0.120396 0.2794)
			(end -0.12065 0.2794)
			(stroke
				(width 0.1)
				(type default)
			)
			(layer "F.Fab")
		)
		(fp_line
			(start 0.120396 0.3048)
			(end 0.120396 0.2794)
			(stroke
				(width 0.1)
				(type default)
			)
			(layer "F.Fab")
		)
		(fp_line
			(start 0.12065 -0.3048)
			(end 0.67945 -0.3048)
			(stroke
				(width 0.1)
				(type default)
			)
			(layer "F.Fab")
		)
		(fp_line
			(start 0.12065 -0.2794)
			(end 0.12065 -0.3048)
			(stroke
				(width 0.1)
				(type default)
			)
			(layer "F.Fab")
		)
		(fp_line
			(start 0.67945 -0.3048)
			(end 0.67945 0.3048)
			(stroke
				(width 0.1)
				(type default)
			)
			(layer "F.Fab")
		)
		(fp_line
			(start 0.67945 0.3048)
			(end 0.120396 0.3048)
			(stroke
				(width 0.1)
				(type default)
			)
			(layer "F.Fab")
		)
		(pad "1" smd circle
			(at -0.40005 0)
			(size 0 0)
			(layers "F.Cu" "F.Mask" "F.Paste")
			(net "P3V3_AUX")
		)
		(pad "2" smd circle
			(at 0.40005 0)
			(size 0 0)
			(layers "F.Cu" "F.Mask" "F.Paste")
			(net "I3C_BMC_SWB_BUF_R_SDA")
		)
	)
	(footprint ""
		(layer "F.Cu")
		(at 369.228878 -394.647166 180)
		(property "Reference" "R4165"
			(at 0 0 180)
			(layer "F.SilkS")
			(hide yes)
			(effects
				(font
					(size 1.27 1.27)
				)
			)
		)
		(property "Value" ""
			(at 0 0 180)
			(layer "F.Fab")
			(effects
				(font
					(size 1.27 1.27)
				)
			)
		)
		(duplicate_pad_numbers_are_jumpers no)
		(fp_line
			(start 0.7874 0.4064)
			(end -0.7874 0.4064)
			(stroke
				(width 0.1524)
				(type default)
			)
			(layer "F.SilkS")
		)
		(fp_line
			(start 0.7874 -0.4064)
			(end 0.7874 0.4064)
			(stroke
				(width 0.1524)
				(type default)
			)
			(layer "F.SilkS")
		)
		(fp_line
			(start -0.7874 0.4064)
			(end -0.7874 -0.4064)
			(stroke
				(width 0.1524)
				(type default)
			)
			(layer "F.SilkS")
		)
		(fp_line
			(start -0.7874 -0.4064)
			(end 0.7874 -0.4064)
			(stroke
				(width 0.1524)
				(type default)
			)
			(layer "F.SilkS")
		)
		(fp_line
			(start 0.67945 0.3048)
			(end 0.120396 0.3048)
			(stroke
				(width 0.1)
				(type default)
			)
			(layer "F.Fab")
		)
		(fp_line
			(start 0.67945 -0.3048)
			(end 0.67945 0.3048)
			(stroke
				(width 0.1)
				(type default)
			)
			(layer "F.Fab")
		)
		(fp_line
			(start 0.12065 -0.2794)
			(end 0.12065 -0.3048)
			(stroke
				(width 0.1)
				(type default)
			)
			(layer "F.Fab")
		)
		(fp_line
			(start 0.12065 -0.3048)
			(end 0.67945 -0.3048)
			(stroke
				(width 0.1)
				(type default)
			)
			(layer "F.Fab")
		)
		(fp_line
			(start 0.120396 0.3048)
			(end 0.120396 0.2794)
			(stroke
				(width 0.1)
				(type default)
			)
			(layer "F.Fab")
		)
		(fp_line
			(start 0.120396 0.2794)
			(end -0.12065 0.2794)
			(stroke
				(width 0.1)
				(type default)
			)
			(layer "F.Fab")
		)
		(fp_line
			(start -0.12065 0.3048)
			(end -0.67945 0.3048)
			(stroke
				(width 0.1)
				(type default)
			)
			(layer "F.Fab")
		)
		(fp_line
			(start -0.12065 0.2794)
			(end -0.12065 0.3048)
			(stroke
				(width 0.1)
				(type default)
			)
			(layer "F.Fab")
		)
		(fp_line
			(start -0.12065 -0.2794)
			(end 0.12065 -0.2794)
			(stroke
				(width 0.1)
				(type default)
			)
			(layer "F.Fab")
		)
		(fp_line
			(start -0.12065 -0.305054)
			(end -0.12065 -0.2794)
			(stroke
				(width 0.1)
				(type default)
			)
			(layer "F.Fab")
		)
		(fp_line
			(start -0.67945 0.3048)
			(end -0.67945 -0.305054)
			(stroke
				(width 0.1)
				(type default)
			)
			(layer "F.Fab")
		)
		(fp_line
			(start -0.67945 -0.305054)
			(end -0.12065 -0.305054)
			(stroke
				(width 0.1)
				(type default)
			)
			(layer "F.Fab")
		)
		(pad "1" smd circle
			(at -0.40005 0 180)
			(size 0 0)
			(layers "F.Cu" "F.Mask" "F.Paste")
			(net "P3V3_AUX")
		)
		(pad "2" smd circle
			(at 0.40005 0 180)
			(size 0 0)
			(layers "F.Cu" "F.Mask" "F.Paste")
			(net "GPU_3V3IO_RSVD4_N")
		)
	)
)
